# T6G (Grand Teton) — schematic netlist excerpt (pin names and nets, part order shuffled) for the footprints in the layout excerpt that follows; sources: Cadence DE-HDL packaged netlist, KiCad conversion of 04192023_DAF0TMB3IC0_F0TG_MB_C_brd_V02_OCP.brd

R6297  Q_RES  10K 1% CHIP  pkg 0402LF  page 178 : A = P3V3_AUX ; B = USB_HUB2_TI_OVERCCUR4

(kicad_pcb
	(version 20260206)
	(generator "pcbnew")
	(generator_version "10.0")
	(general
		(thickness 1.6)
		(legacy_teardrops no)
	)
	(paper "A4")
	(title_block
		(title "04192023_DAF0TMB3IC0_F0TG_MB_C_brd_V02_OCP.brd")
		(comment 1 "Grand Teton / footprints 3974-3974 of 8354")
	)
	(layers
		(0 "F.Cu" signal "TOP")
		(4 "In1.Cu" signal "GND")
		(6 "In2.Cu" signal "IN1")
		(8 "In3.Cu" signal "GND1")
		(10 "In4.Cu" signal "IN2")
		(12 "In5.Cu" signal "GND2")
		(14 "In6.Cu" signal "IN3")
		(16 "In7.Cu" signal "GND3")
		(18 "In8.Cu" signal "VCC")
		(20 "In9.Cu" signal "VCC1")
		(22 "In10.Cu" signal "GND4")
		(24 "In11.Cu" signal "IN4")
		(26 "In12.Cu" signal "GND5")
		(28 "In13.Cu" signal "IN5")
		(30 "In14.Cu" signal "GND6")
		(32 "In15.Cu" signal "IN6")
		(34 "In16.Cu" signal "GND7")
		(2 "B.Cu" signal "BOTTOM")
		(9 "F.Adhes" user "F.Adhesive")
		(11 "B.Adhes" user "B.Adhesive")
		(13 "F.Paste" user "Package Geometry/Pastemask Top")
		(15 "B.Paste" user "Package Geometry/Pastemask Bottom")
		(5 "F.SilkS" user "Ref Des/Silkscreen Top")
		(7 "B.SilkS" user "Ref Des/Silkscreen Bottom")
		(1 "F.Mask" user "Board Geometry/Soldermask Top")
		(3 "B.Mask" user "Board Geometry/Soldermask Bottom")
		(17 "Dwgs.User" user "User.Drawings")
		(19 "Cmts.User" user "User.Comments")
		(21 "Eco1.User" user "User.Eco1")
		(23 "Eco2.User" user "User.Eco2")
		(25 "Edge.Cuts" user "Board Geometry/Outline")
		(27 "Margin" user)
		(31 "F.CrtYd" user "Package Geometry/Place Bound Top")
		(29 "B.CrtYd" user "Package Geometry/Place Bound Bottom")
		(35 "F.Fab" user "Ref Des/Assembly Top")
		(33 "B.Fab" user "Ref Des/Assembly Bottom")
	)
	(footprint ""
		(layer "F.Cu")
		(at 118.617746 -52.48148 180)
		(property "Reference" "R6297"
			(at 0 0 180)
			(layer "F.SilkS")
			(hide yes)
			(effects
				(font
					(size 1.27 1.27)
				)
			)
		)
		(property "Value" ""
			(at 0 0 180)
			(layer "F.Fab")
			(effects
				(font
					(size 1.27 1.27)
				)
			)
		)
		(duplicate_pad_numbers_are_jumpers no)
		(fp_line
			(start 0.7874 0.4064)
			(end -0.7874 0.4064)
			(stroke
				(width 0.1524)
				(type default)
			)
			(layer "F.SilkS")
		)
		(fp_line
			(start 0.7874 -0.4064)
			(end 0.7874 0.4064)
			(stroke
				(width 0.1524)
				(type default)
			)
			(layer "F.SilkS")
		)
		(fp_line
			(start -0.7874 0.4064)
			(end -0.7874 -0.4064)
			(stroke
				(width 0.1524)
				(type default)
			)
			(layer "F.SilkS")
		)
		(fp_line
			(start -0.7874 -0.4064)
			(end 0.7874 -0.4064)
			(stroke
				(width 0.1524)
				(type default)
			)
			(layer "F.SilkS")
		)
		(fp_line
			(start 0.67945 0.3048)
			(end 0.120396 0.3048)
			(stroke
				(width 0.1)
				(type default)
			)
			(layer "F.Fab")
		)
		(fp_line
			(start 0.67945 -0.3048)
			(end 0.67945 0.3048)
			(stroke
				(width 0.1)
				(type default)
			)
			(layer "F.Fab")
		)
		(fp_line
			(start 0.12065 -0.2794)
			(end 0.12065 -0.3048)
			(stroke
				(width 0.1)
				(type default)
			)
			(layer "F.Fab")
		)
		(fp_line
			(start 0.12065 -0.3048)
			(end 0.67945 -0.3048)
			(stroke
				(width 0.1)
				(type default)
			)
			(layer "F.Fab")
		)
		(fp_line
			(start 0.120396 0.3048)
			(end 0.120396 0.2794)
			(stroke
				(width 0.1)
				(type default)
			)
			(layer "F.Fab")
		)
		(fp_line
			(start 0.120396 0.2794)
			(end -0.12065 0.2794)
			(stroke
				(width 0.1)
				(type default)
			)
			(layer "F.Fab")
		)
		(fp_line
			(start -0.12065 0.3048)
			(end -0.67945 0.3048)
			(stroke
				(width 0.1)
				(type default)
			)
			(layer "F.Fab")
		)
		(fp_line
			(start -0.12065 0.2794)
			(end -0.12065 0.3048)
			(stroke
				(width 0.1)
				(type default)
			)
			(layer "F.Fab")
		)
		(fp_line
			(start -0.12065 -0.2794)
			(end 0.12065 -0.2794)
			(stroke
				(width 0.1)
				(type default)
			)
			(layer "F.Fab")
		)
		(fp_line
			(start -0.12065 -0.305054)
			(end -0.12065 -0.2794)
			(stroke
				(width 0.1)
				(type default)
			)
			(layer "F.Fab")
		)
		(fp_line
			(start -0.67945 0.3048)
			(end -0.67945 -0.305054)
			(stroke
				(width 0.1)
				(type default)
			)
			(layer "F.Fab")
		)
		(fp_line
			(start -0.67945 -0.305054)
			(end -0.12065 -0.305054)
			(stroke
				(width 0.1)
				(type default)
			)
			(layer "F.Fab")
		)
		(pad "1" smd circle
			(at -0.40005 0 180)
			(size 0 0)
			(layers "F.Cu" "F.Mask" "F.Paste")
			(net "P3V3_AUX")
		)
		(pad "2" smd circle
			(at 0.40005 0 180)
			(size 0 0)
			(layers "F.Cu" "F.Mask" "F.Paste")
			(net "USB_HUB2_TI_OVERCCUR4")
		)
	)
)
